# T6G (Grand Teton) — schematic netlist excerpt (pin names and nets, part order shuffled) for the footprints in the layout excerpt that follows; sources: Cadence DE-HDL packaged netlist, KiCad conversion of 04192023_DAF0TMB3IC0_F0TG_MB_C_brd_V02_OCP.brd

R2628  Q_RES  0 5% CHIP  pkg 0402LF  page 267 : A = P12V_HSC_TEMP_ALERT_N ; B = P12V_HSC_TEMP_ALERT_R_N

(kicad_pcb
	(version 20260206)
	(generator "pcbnew")
	(generator_version "10.0")
	(general
		(thickness 1.6)
		(legacy_teardrops no)
	)
	(paper "A4")
	(title_block
		(title "04192023_DAF0TMB3IC0_F0TG_MB_C_brd_V02_OCP.brd")
		(comment 1 "Grand Teton / footprints 1310-1310 of 8354")
	)
	(layers
		(0 "F.Cu" signal "TOP")
		(4 "In1.Cu" signal "GND")
		(6 "In2.Cu" signal "IN1")
		(8 "In3.Cu" signal "GND1")
		(10 "In4.Cu" signal "IN2")
		(12 "In5.Cu" signal "GND2")
		(14 "In6.Cu" signal "IN3")
		(16 "In7.Cu" signal "GND3")
		(18 "In8.Cu" signal "VCC")
		(20 "In9.Cu" signal "VCC1")
		(22 "In10.Cu" signal "GND4")
		(24 "In11.Cu" signal "IN4")
		(26 "In12.Cu" signal "GND5")
		(28 "In13.Cu" signal "IN5")
		(30 "In14.Cu" signal "GND6")
		(32 "In15.Cu" signal "IN6")
		(34 "In16.Cu" signal "GND7")
		(2 "B.Cu" signal "BOTTOM")
		(9 "F.Adhes" user "F.Adhesive")
		(11 "B.Adhes" user "B.Adhesive")
		(13 "F.Paste" user "Package Geometry/Pastemask Top")
		(15 "B.Paste" user "Package Geometry/Pastemask Bottom")
		(5 "F.SilkS" user "Ref Des/Silkscreen Top")
		(7 "B.SilkS" user "Ref Des/Silkscreen Bottom")
		(1 "F.Mask" user "Board Geometry/Soldermask Top")
		(3 "B.Mask" user "Board Geometry/Soldermask Bottom")
		(17 "Dwgs.User" user "User.Drawings")
		(19 "Cmts.User" user "User.Comments")
		(21 "Eco1.User" user "User.Eco1")
		(23 "Eco2.User" user "User.Eco2")
		(25 "Edge.Cuts" user "Board Geometry/Outline")
		(27 "Margin" user)
		(31 "F.CrtYd" user "Package Geometry/Place Bound Top")
		(29 "B.CrtYd" user "Package Geometry/Place Bound Bottom")
		(35 "F.Fab" user "Ref Des/Assembly Top")
		(33 "B.Fab" user "Ref Des/Assembly Bottom")
	)
	(footprint ""
		(layer "F.Cu")
		(at 281.818588 -394.444982 -90)
		(property "Reference" "R2628"
			(at 0 0 270)
			(layer "F.SilkS")
			(hide yes)
			(effects
				(font
					(size 1.27 1.27)
				)
			)
		)
		(property "Value" ""
			(at 0 0 270)
			(layer "F.Fab")
			(effects
				(font
					(size 1.27 1.27)
				)
			)
		)
		(duplicate_pad_numbers_are_jumpers no)
		(fp_line
			(start -0.7874 0.4064)
			(end -0.7874 -0.4064)
			(stroke
				(width 0.1524)
				(type default)
			)
			(layer "F.SilkS")
		)
		(fp_line
			(start 0.7874 0.4064)
			(end -0.7874 0.4064)
			(stroke
				(width 0.1524)
				(type default)
			)
			(layer "F.SilkS")
		)
		(fp_line
			(start -0.7874 -0.4064)
			(end 0.7874 -0.4064)
			(stroke
				(width 0.1524)
				(type default)
			)
			(layer "F.SilkS")
		)
		(fp_line
			(start 0.7874 -0.4064)
			(end 0.7874 0.4064)
			(stroke
				(width 0.1524)
				(type default)
			)
			(layer "F.SilkS")
		)
		(fp_line
			(start -0.67945 0.3048)
			(end -0.67945 -0.305054)
			(stroke
				(width 0.1)
				(type default)
			)
			(layer "F.Fab")
		)
		(fp_line
			(start -0.12065 0.3048)
			(end -0.67945 0.3048)
			(stroke
				(width 0.1)
				(type default)
			)
			(layer "F.Fab")
		)
		(fp_line
			(start 0.120396 0.3048)
			(end 0.120396 0.2794)
			(stroke
				(width 0.1)
				(type default)
			)
			(layer "F.Fab")
		)
		(fp_line
			(start 0.67945 0.3048)
			(end 0.120396 0.3048)
			(stroke
				(width 0.1)
				(type default)
			)
			(layer "F.Fab")
		)
		(fp_line
			(start -0.12065 0.2794)
			(end -0.12065 0.3048)
			(stroke
				(width 0.1)
				(type default)
			)
			(layer "F.Fab")
		)
		(fp_line
			(start 0.120396 0.2794)
			(end -0.12065 0.2794)
			(stroke
				(width 0.1)
				(type default)
			)
			(layer "F.Fab")
		)
		(fp_line
			(start -0.12065 -0.2794)
			(end 0.12065 -0.2794)
			(stroke
				(width 0.1)
				(type default)
			)
			(layer "F.Fab")
		)
		(fp_line
			(start 0.12065 -0.2794)
			(end 0.12065 -0.3048)
			(stroke
				(width 0.1)
				(type default)
			)
			(layer "F.Fab")
		)
		(fp_line
			(start 0.12065 -0.3048)
			(end 0.67945 -0.3048)
			(stroke
				(width 0.1)
				(type default)
			)
			(layer "F.Fab")
		)
		(fp_line
			(start 0.67945 -0.3048)
			(end 0.67945 0.3048)
			(stroke
				(width 0.1)
				(type default)
			)
			(layer "F.Fab")
		)
		(fp_line
			(start -0.67945 -0.305054)
			(end -0.12065 -0.305054)
			(stroke
				(width 0.1)
				(type default)
			)
			(layer "F.Fab")
		)
		(fp_line
			(start -0.12065 -0.305054)
			(end -0.12065 -0.2794)
			(stroke
				(width 0.1)
				(type default)
			)
			(layer "F.Fab")
		)
		(pad "1" smd circle
			(at -0.40005 0 270)
			(size 0 0)
			(layers "F.Cu" "F.Mask" "F.Paste")
			(net "P12V_HSC_TEMP_ALERT_N")
		)
		(pad "2" smd circle
			(at 0.40005 0 270)
			(size 0 0)
			(layers "F.Cu" "F.Mask" "F.Paste")
			(net "P12V_HSC_TEMP_ALERT_R_N")
		)
	)
)
